FILE_TYPE = MULTI_PHYS_TABLE;

PART 'DIODE_2E'
CLASS=DISCRETE

{========================================================================================}
:CLS_PN          = JEDEC_TYPE               | ALT_SYMBOLS                | DESCRIPTION                                                            | CPN_STATUS ;
{========================================================================================}
 'CL1003702A'    = 'SOD323'                 | '(SOD323)'                 | 'DIODE, ZENER, 200 MW, 9.1 V'                                          | ''        
 'CL1003703A'    = 'A2_CR094_P383'          | '(A2_CR094_P383)'          | 'DIODE, ZENER, 3W, 200V'                                               | ''        
 'G122-10006-01' = 'SMC_CR_106X063'         | '(SMC_CR_106X063)'         | 'DIO, ZENER, 500 MW, 18V, +/-5%, SOD-123'                              | ''        
 'G122-10004-01' = 'SMC_CR_169X103_V3'      | '(SMC_CR_169X103_V3)'      | 'DIO, ZENER, 1.5W, 16 V, +/-5%, SMA'                                   | ''        
 'G122-10005-01' = 'SMC_CR_169X103_V3'      | '(SMC_CR_169X103_V3)'      | 'DIO, ZENER, 1.5W, 22 V, +/-5%, SMA'                                   | ''        
 'G122-10034-01' = 'SMC_CR_170X143'         | '(SMC_CR_170X143)'         | 'DIO, TVS, SMBT70A, 600W, 70VRWM, 100VC, 5.3A,SMB'                     | ''        
 'G122-10035-01' = 'SMC_CR_270X232'         | '(SMC_CR_270X232)'         | 'DIO, TVS, SMCJ60A, 1500W, 60VRWM, 96.8VC, 15.5A,SMB'                  | ''        
 'G122-10047-01' = 'SMC_CR_169X102'         | '(SMC_CR_169X102)'         | 'DIO, SCHOTTKY POWER RECTIFIER, MBRAF440, 40V, 4A, 5.4X2.8MM, SMA-FL'  | ''        
 'G122-10051-01' = 'SMC_CR_270X230'         | '(SMC_CR_270X230)'         | 'DIO, TVS, 1.5SMC68A, 58.1VRWM, 16.3A, 92VC, 1500W, SMC'               | 'REJECTED'
 'G122-10052-01' = 'SMC_CR_270X230'         | '(SMC_CR_270X230)'         | 'DIO, TVS, 1.5SMC15A, 12.8VRWM, 71A, 21.2VC, 1500W, SMC'               | ''        
 'G122-10049-01' = 'SMC_CR_170X140_V2'      | '(SMC_CR_170X140_V2)'      | 'DIO, ZENER, 1SMB5917B, 4.7V, 319MA, 5%, 3W, SMB'                      | ''        
 'G122-10050-01' = 'SMC_CR_170X140_V2'      | '(SMC_CR_170X140_V2)'      | 'DIO, ZENER, 1SMB5925B, 10V, 150MA, 5%, 3W, SMB'                       | ''        
 'G122-10075-01' = 'SOD923_V1'              | '(SOD923_V1)'              | 'DIO,ZENER,NZ9F5V1T5G,5.1V,0.2W,SOD923'                                | ''        
 'G122-10091-01' = 'SMC_CR_270X232'         | '(SMC_CR_270X232)'         | 'DIO,TVS,SMCJ64A,64VRWM,103VC,14.6A,SMC'                               | ''        
 'G122-10088-01' = 'SMC_CR_138X057'         | '(SMC_CR_138X057)'         | 'DIO,ZENER,ZMM6V2,6.2V,5MA,LL-34'                                      | ''        
 'G122-10083-01' = 'SMC_CR_270X232'         | '(SMC_CR_270X232)'         | 'DIO,TVS,SMCJ16A,16V,1MA,SMC,SMT'                                      | ''        
 'G122-10102-01' = 'SMC_CR_270X230'         | '(SMC_CR_270X230)'         | 'DIO,TVS,1.5SMC16A,13.6VRWM,67A,22.5VC,1500W,SMC'                      | ''        
 'G122-10082-01' = 'SMC_CR_270X232'         | '(SMC_CR_270X232)'         | 'DIO,TVS,SMCJ6.0A,6V,1MA,SMC,SMT'                                      | ''        
 'G122-10109-01' = 'SOD323_V4_H031'         | '(SOD323_V4_H031)'         | 'DIO,ZENER,BZX84J-B4V7,115,4.7V,5MA,SOD323F'                           | ''        
 'G122-10128-01' = 'SOD323_V4_H031'         | '(SOD323_V4_H031)'         | 'DIO,ZENER,BZX84J-B4V3,115,4.3V,5MA,SOD323F'                           | ''        
 'G122-10111-01' = 'SOD123V3_H053'          | '(SOD123V3_H053)'          | 'DIO,ZENER,15V,500MW,5%,SOD123'                                        | ''        
 'G122-10112-01' = 'SOD323_V4'              | '(SOD323_V4)'              | 'DIO,ZENER,5.1V,300MW,2%,SOD123'                                       | ''        
 'G122-10134-01' = 'SMC_CR_170X102'         | '(SMC_CR_170X102)'         | 'DIO,ZENER,1SMA5938BT3G,36V,5%,1.5W,SMA'                               | ''        
 'G122-10135-01' = 'SMC_CR_170X102'         | '(SMC_CR_170X102)'         | 'DIO,ZENER,1SMA5939BT3G,39V,5%,1.5W,SMA'                               | ''        
 'G122-10136-01' = 'SMC_CR_170X102'         | '(SMC_CR_170X102)'         | 'DIO,ZENER,1SMA5937BT3G,33V,5%,1.5W,SMA'                               | ''        
 'G122-10139-01' = 'SMC_CR_170X140_V2_H097' | '(SMC_CR_170X140_V2_H097)' | 'DIO,1SMB54A,TVS,54V,600W,SMB'                                         | 'REJECTED'
 'G122-10081-01' = 'SMC_CR_170X143_V3'      | '(SMC_CR_170X143_V3)'      | 'DIO,SMBJ14A,TRANSIENT VOLTAGE SUPR05PRESSOR,14V,SMB'                  | ''        
 'G122-10023-01' = 'SMC_CR_172X143'         | '(SMC_CR_172X143)'         | 'DIO,SMBJ15A,TRANSIENT VOLTAGE SUPR05PRESSOR,15V,SMB'                  | ''        
 'G122-10144-01' = 'SOD123V3_H050'          | '(SOD123V3_H050)'          | 'DIO,ZENER,MMSZ4686,3.9V,0.00005A,5%,0.5W,SOD-123,SMD'                 | 'REJECTED'
 'G122-10145-01' = 'SOD123V3_H050'          | '(SOD123V3_H050)'          | 'DIO,ZENER,MMSZ4688,4.7V,0.00005A,5%,0.5W,SOD-123,SMD'                 | 'REJECTED'
 'G122-10146-01' = 'SOD123V3_H050'          | '(SOD123V3_H050)'          | 'DIO,ZENER,MMSZ4688,6.8V,0.00005A,5%,0.5W,SOD-123,SMD'                 | 'REJECTED'
 'G122-10147-01' = 'SMC_CR_170X140_V2_H097' | '(SMC_CR_170X140_V2_H097)' | 'DIO,1SMB48A,TVS,48V,600W,SMB'                                         | 'REJECTED'
 'G122-10152-01' = 'SOD123_V6'              | '(SOD123_V6)'              | 'DIO,SMF4L14A,TRANSIENT_VOLTAGE_SUPR05PRESSOR,14V,400W,SOD123FL'       | ''        
 'G122-10154-01' = 'SMC_CR_170X140'         | '(SMC_CR_170X140)'         | 'DIO,ZENER, 1SMB5945BT3G,68V,5%,3W,SMB'                                | ''        
 'G122-10160-01' = 'SMC_CR_169X103_V2'      | '(SMC_CR_169X103_V2)'      | 'DIO,TVS,SMAJ16CA,16V,400W,SMA'                                        | ''        
 'G122-10169-01' = 'SMC_CR_169X103_V2_H094' | '(SMC_CR_169X103_V2_H094)' | 'DIO,ZENER,SMAZ36,36V,5%,1W,SMA'                                       | ''        
 'G122-10170-01' = 'SOD123V3_H053'          | '(SOD123V3_H053)'          | 'DIODE, ZENER, 6.8V, 500MW, SOD-123'                                   | ''        
 'G122-10174-01' = 'SMC_CR_271X232'         | '(SMC_CR_271X232)'         | 'DIO,TVS,SMCJ58A,58V,16A,SMC,ROHS COMPLIANT'                           | ''        
 'G122-10175-01' = 'SMC_CR_270X232_V2'      | '(SMC_CR_270X232_V2)'      | 'DIO,TRANSIENT VOLTAGE SUPR05PRESSOR DIODES,60V,SMC'                   | ''        
 'A122-00001-AW' = 'SMC_CR_106X069'         | '(SMC_CR_106X069)'         | 'DIO,TVS,SMF5.0A,5V,400UA,SOD-123FL'                                   | ''        
 'A122-00003-AW' = 'SOD323_V6'              | '(SOD323_V6)'              | 'DIO,TVS,PSD03,3.3V,125UA,SOD-323'                                     | ''        
 'G122-10119-01' = 'SOD323_V5'              | '(SOD323_V5)'              | 'DIO,ZENER,3.3V,5MA,SOD323'                                            | ''        
 'G122-10176-01' = 'SMC_CR_270X232'         | '(SMC_CR_270X232)'         | 'DIO,TVS,SMCJ13A,13V,27.9A,SMC'                                        | ''        
 'G122-10177-01' = 'SMC_CR_270X232'         | '(SMC_CR_270X232)'         | 'DIO,TVS,SMCJ14A,14V,64A,SMC'                                          | ''        
 'G122-10178-01' = 'SMC_CR_270X232'         | '(SMC_CR_270X232)'         | 'DIO, SCHOTTKY, 30V, 5A, SMC'                                          | ''        
 'G122-10188-01' = 'SMC_CR_169X103_V2'      | '(SMC_CR_169X103_V2)'      | 'DIO,TVS,SMAJ5.0A,5V,43.5A,SMC'                                        | ''        
 'G122-10189-01' = 'SMC_CR_169X103_V2'      | '(SMC_CR_169X103_V2)'      | 'DIO,TVS,SMAJ15A,15V,16.4A,SMC'                                        | ''        
 'G122-10190-01' = 'SMC_CR_270X232_V1'      | '(SMC_CR_270X232_V1)'      | 'DIO,TVS,SMDJ,12V,0.001A,DO214B'                                       | ''        
 'G122-10192-01' = 'SMC_CR_169X102_V2'      | '(SMC_CR_169X102_V2)'      | 'DIO,TVS,SMAJ13A,13V,18.6A,SMA'                                        | ''        
 'G122-10195-01' = 'SOD123V3_H053'          | '(SOD123V3_H053)'          | 'DIO,ZENER,13V,0.05MA,500MW,SOD123'                                    | ''        
 'G122-10196-01' = 'SMC_CR_169X102_V2'      | '(SMC_CR_169X102_V2)'      | 'DIO,SMA6J13A,TRANSIENT VOLTAGE SUPPRESSOR,13V,SMA,-55C~150C,VC=20.4V' | ''        
 'G122-10200-01' = 'SMC_CR_169X102_V2'      | '(SMC_CR_169X102_V2)'      | 'DIO,TVS,SMAJ120A,120V,SMA'                                            | ''        

END_PART

END.

